# SCM (Grand Teton) — schematic netlist excerpt (pin names and nets, part order shuffled) for the footprints in the layout excerpt that follows; sources: Cadence DE-HDL packaged netlist, KiCad conversion of 12092022_DA0F0TMDCD0_F0T_Management_Board_D_brd_V3_OCP.brd

C114  Q_CAP  1UF 25V 10% X6S  pkg C0402  page 16 : A = P1V8_AUX ; B = GND
R662  Q_RES  10K 1% EMPTY  pkg 0402LF  page 21 : A = P3V3_AUX ; B = EMMC_DT7_R

(kicad_pcb
	(version 20260206)
	(generator "pcbnew")
	(generator_version "10.0")
	(general
		(thickness 1.6)
		(legacy_teardrops no)
	)
	(paper "A4")
	(title_block
		(title "12092022_DA0F0TMDCD0_F0T_Management_Board_D_brd_V3_OCP.brd")
		(comment 1 "Grand Teton / footprints 561-562 of 1440")
	)
	(layers
		(0 "F.Cu" signal "TOP")
		(4 "In1.Cu" signal "GND")
		(6 "In2.Cu" signal "IN1")
		(8 "In3.Cu" signal "GND1")
		(10 "In4.Cu" signal "IN2")
		(12 "In5.Cu" signal "VCC")
		(14 "In6.Cu" signal "VCC1")
		(16 "In7.Cu" signal "IN3")
		(18 "In8.Cu" signal "GND2")
		(20 "In9.Cu" signal "IN4")
		(22 "In10.Cu" signal "GND3")
		(2 "B.Cu" signal "BOTTOM")
		(9 "F.Adhes" user "F.Adhesive")
		(11 "B.Adhes" user "B.Adhesive")
		(13 "F.Paste" user "Package Geometry/Pastemask Top")
		(15 "B.Paste" user "Package Geometry/Pastemask Bottom")
		(5 "F.SilkS" user "Ref Des/Silkscreen Top")
		(7 "B.SilkS" user "Ref Des/Silkscreen Bottom")
		(1 "F.Mask" user "Board Geometry/Soldermask Top")
		(3 "B.Mask" user "Board Geometry/Soldermask Bottom")
		(17 "Dwgs.User" user "User.Drawings")
		(19 "Cmts.User" user "User.Comments")
		(21 "Eco1.User" user "User.Eco1")
		(23 "Eco2.User" user "User.Eco2")
		(25 "Edge.Cuts" user "Board Geometry/Outline")
		(27 "Margin" user)
		(31 "F.CrtYd" user "Package Geometry/Place Bound Top")
		(29 "B.CrtYd" user "Package Geometry/Place Bound Bottom")
		(35 "F.Fab" user "Ref Des/Assembly Top")
		(33 "B.Fab" user "Ref Des/Assembly Bottom")
	)
	(footprint ""
		(layer "F.Cu")
		(at 70.619112 -35.258756 90)
		(property "Reference" "C114"
			(at 0 0 90)
			(layer "F.SilkS")
			(hide yes)
			(effects
				(font
					(size 1.27 1.27)
				)
			)
		)
		(property "Value" ""
			(at 0 0 90)
			(layer "F.Fab")
			(effects
				(font
					(size 1.27 1.27)
				)
			)
		)
		(duplicate_pad_numbers_are_jumpers no)
		(fp_line
			(start 0.7874 -0.4064)
			(end 0.7874 0.4064)
			(stroke
				(width 0.1524)
				(type default)
			)
			(layer "F.SilkS")
		)
		(fp_line
			(start -0.7874 -0.4064)
			(end 0.7874 -0.4064)
			(stroke
				(width 0.1524)
				(type default)
			)
			(layer "F.SilkS")
		)
		(fp_line
			(start 0.7874 0.4064)
			(end -0.7874 0.4064)
			(stroke
				(width 0.1524)
				(type default)
			)
			(layer "F.SilkS")
		)
		(fp_line
			(start -0.7874 0.4064)
			(end -0.7874 -0.4064)
			(stroke
				(width 0.1524)
				(type default)
			)
			(layer "F.SilkS")
		)
		(fp_line
			(start -0.12065 -0.305054)
			(end -0.12065 -0.2794)
			(stroke
				(width 0.1)
				(type default)
			)
			(layer "F.Fab")
		)
		(fp_line
			(start -0.67945 -0.305054)
			(end -0.12065 -0.305054)
			(stroke
				(width 0.1)
				(type default)
			)
			(layer "F.Fab")
		)
		(fp_line
			(start 0.67945 -0.3048)
			(end 0.67945 0.3048)
			(stroke
				(width 0.1)
				(type default)
			)
			(layer "F.Fab")
		)
		(fp_line
			(start 0.12065 -0.3048)
			(end 0.67945 -0.3048)
			(stroke
				(width 0.1)
				(type default)
			)
			(layer "F.Fab")
		)
		(fp_line
			(start 0.12065 -0.2794)
			(end 0.12065 -0.3048)
			(stroke
				(width 0.1)
				(type default)
			)
			(layer "F.Fab")
		)
		(fp_line
			(start -0.12065 -0.2794)
			(end 0.12065 -0.2794)
			(stroke
				(width 0.1)
				(type default)
			)
			(layer "F.Fab")
		)
		(fp_line
			(start 0.120396 0.2794)
			(end -0.12065 0.2794)
			(stroke
				(width 0.1)
				(type default)
			)
			(layer "F.Fab")
		)
		(fp_line
			(start -0.12065 0.2794)
			(end -0.12065 0.3048)
			(stroke
				(width 0.1)
				(type default)
			)
			(layer "F.Fab")
		)
		(fp_line
			(start 0.67945 0.3048)
			(end 0.120396 0.3048)
			(stroke
				(width 0.1)
				(type default)
			)
			(layer "F.Fab")
		)
		(fp_line
			(start 0.120396 0.3048)
			(end 0.120396 0.2794)
			(stroke
				(width 0.1)
				(type default)
			)
			(layer "F.Fab")
		)
		(fp_line
			(start -0.12065 0.3048)
			(end -0.67945 0.3048)
			(stroke
				(width 0.1)
				(type default)
			)
			(layer "F.Fab")
		)
		(fp_line
			(start -0.67945 0.3048)
			(end -0.67945 -0.305054)
			(stroke
				(width 0.1)
				(type default)
			)
			(layer "F.Fab")
		)
		(pad "1" smd circle
			(at -0.40005 0 90)
			(size 0 0)
			(layers "F.Cu" "F.Mask" "F.Paste")
			(net "P1V8_AUX")
		)
		(pad "2" smd circle
			(at 0.40005 0 90)
			(size 0 0)
			(layers "F.Cu" "F.Mask" "F.Paste")
			(net "GND")
		)
	)
	(footprint ""
		(layer "F.Cu")
		(at 29.27604 -68.504054 90)
		(property "Reference" "R662"
			(at 0 0 90)
			(layer "F.SilkS")
			(hide yes)
			(effects
				(font
					(size 1.27 1.27)
				)
			)
		)
		(property "Value" ""
			(at 0 0 90)
			(layer "F.Fab")
			(effects
				(font
					(size 1.27 1.27)
				)
			)
		)
		(duplicate_pad_numbers_are_jumpers no)
		(fp_line
			(start 0.7874 -0.4064)
			(end 0.7874 0.4064)
			(stroke
				(width 0.1524)
				(type default)
			)
			(layer "F.SilkS")
		)
		(fp_line
			(start -0.7874 -0.4064)
			(end 0.7874 -0.4064)
			(stroke
				(width 0.1524)
				(type default)
			)
			(layer "F.SilkS")
		)
		(fp_line
			(start 0.7874 0.4064)
			(end -0.7874 0.4064)
			(stroke
				(width 0.1524)
				(type default)
			)
			(layer "F.SilkS")
		)
		(fp_line
			(start -0.7874 0.4064)
			(end -0.7874 -0.4064)
			(stroke
				(width 0.1524)
				(type default)
			)
			(layer "F.SilkS")
		)
		(fp_line
			(start -0.12065 -0.305054)
			(end -0.12065 -0.2794)
			(stroke
				(width 0.1)
				(type default)
			)
			(layer "F.Fab")
		)
		(fp_line
			(start -0.67945 -0.305054)
			(end -0.12065 -0.305054)
			(stroke
				(width 0.1)
				(type default)
			)
			(layer "F.Fab")
		)
		(fp_line
			(start 0.67945 -0.3048)
			(end 0.67945 0.3048)
			(stroke
				(width 0.1)
				(type default)
			)
			(layer "F.Fab")
		)
		(fp_line
			(start 0.12065 -0.3048)
			(end 0.67945 -0.3048)
			(stroke
				(width 0.1)
				(type default)
			)
			(layer "F.Fab")
		)
		(fp_line
			(start 0.12065 -0.2794)
			(end 0.12065 -0.3048)
			(stroke
				(width 0.1)
				(type default)
			)
			(layer "F.Fab")
		)
		(fp_line
			(start -0.12065 -0.2794)
			(end 0.12065 -0.2794)
			(stroke
				(width 0.1)
				(type default)
			)
			(layer "F.Fab")
		)
		(fp_line
			(start 0.120396 0.2794)
			(end -0.12065 0.2794)
			(stroke
				(width 0.1)
				(type default)
			)
			(layer "F.Fab")
		)
		(fp_line
			(start -0.12065 0.2794)
			(end -0.12065 0.3048)
			(stroke
				(width 0.1)
				(type default)
			)
			(layer "F.Fab")
		)
		(fp_line
			(start 0.67945 0.3048)
			(end 0.120396 0.3048)
			(stroke
				(width 0.1)
				(type default)
			)
			(layer "F.Fab")
		)
		(fp_line
			(start 0.120396 0.3048)
			(end 0.120396 0.2794)
			(stroke
				(width 0.1)
				(type default)
			)
			(layer "F.Fab")
		)
		(fp_line
			(start -0.12065 0.3048)
			(end -0.67945 0.3048)
			(stroke
				(width 0.1)
				(type default)
			)
			(layer "F.Fab")
		)
		(fp_line
			(start -0.67945 0.3048)
			(end -0.67945 -0.305054)
			(stroke
				(width 0.1)
				(type default)
			)
			(layer "F.Fab")
		)
		(pad "1" smd circle
			(at -0.40005 0 90)
			(size 0 0)
			(layers "F.Cu" "F.Mask" "F.Paste")
			(net "P3V3_AUX")
		)
		(pad "2" smd circle
			(at 0.40005 0 90)
			(size 0 0)
			(layers "F.Cu" "F.Mask" "F.Paste")
			(net "EMMC_DT7_R")
		)
	)
)
